(kicad_pcb
	(version 20260206)
	(generator "pcbnew")
	(generator_version "10.0")
	(general
		(thickness 1.6)
		(legacy_teardrops no)
	)
	(paper "A4")
	(title_block
		(title "panther-plus-userver — 13130-1b_20150205.brd")
		(comment 1 "Honey Badger (Wiwynn) / footprints 333-340 of 1509")
	)
	(layers
		(0 "F.Cu" signal "TOP")
		(4 "In1.Cu" signal "L2")
		(6 "In2.Cu" signal "L3")
		(8 "In3.Cu" signal "L4")
		(10 "In4.Cu" signal "L5")
		(12 "In5.Cu" signal "L6")
		(14 "In6.Cu" signal "L7")
		(16 "In7.Cu" signal "L8")
		(18 "In8.Cu" signal "L9")
		(20 "In9.Cu" signal "L10")
		(22 "In10.Cu" signal "L11")
		(2 "B.Cu" signal "BOTTOM")
		(9 "F.Adhes" user "F.Adhesive")
		(11 "B.Adhes" user "B.Adhesive")
		(13 "F.Paste" user "Package Geometry/Pastemask Top")
		(15 "B.Paste" user "Package Geometry/Pastemask Bottom")
		(5 "F.SilkS" user "Ref Des/Silkscreen Top")
		(7 "B.SilkS" user "Ref Des/Silkscreen Bottom")
		(1 "F.Mask" user "Board Geometry/Soldermask Top")
		(3 "B.Mask" user "Board Geometry/Soldermask Bottom")
		(17 "Dwgs.User" user "User.Drawings")
		(19 "Cmts.User" user "User.Comments")
		(21 "Eco1.User" user "User.Eco1")
		(23 "Eco2.User" user "User.Eco2")
		(25 "Edge.Cuts" user "Board Geometry/Outline")
		(27 "Margin" user)
		(31 "F.CrtYd" user "Package Geometry/Place Bound Top")
		(29 "B.CrtYd" user "Package Geometry/Place Bound Bottom")
		(35 "F.Fab" user "Ref Des/Assembly Top")
		(33 "B.Fab" user "Ref Des/Assembly Bottom")
	)
	(footprint ""
		(layer "F.Cu")
		(at 40.2082 -46.6598)
		(property "Reference" "U7"
			(at 0 0 0)
			(layer "F.SilkS")
			(hide yes)
			(effects
				(font
					(size 1.27 1.27)
				)
			)
		)
		(property "Value" "SN74LVC1G14DCKR-GP"
			(at 0 -8.0772 0)
			(unlocked yes)
			(layer "F.Fab")
			(hide yes)
			(effects
				(font
					(size 1.016 1.016)
					(thickness 0.1524)
				)
			)
		)
		(property "Device Type" "SC70-5H44"
			(at 0 -9.6012 0)
			(unlocked yes)
			(layer "F.Fab")
			(hide yes)
			(effects
				(font
					(size 1.016 1.016)
					(thickness 0.1524)
				)
			)
		)
		(duplicate_pad_numbers_are_jumpers no)
		(fp_line
			(start -1.0033 -0.3302)
			(end 1.0033 -0.3302)
			(stroke
				(width 0.1524)
				(type default)
			)
			(layer "F.SilkS")
		)
		(fp_line
			(start -1.0033 0.3302)
			(end -1.0033 -0.3302)
			(stroke
				(width 0.1524)
				(type default)
			)
			(layer "F.SilkS")
		)
		(fp_line
			(start 1.0033 -0.3302)
			(end 1.0033 0.3302)
			(stroke
				(width 0.1524)
				(type default)
			)
			(layer "F.SilkS")
		)
		(fp_line
			(start 1.0033 0.3302)
			(end -1.0033 0.3302)
			(stroke
				(width 0.1524)
				(type default)
			)
			(layer "F.SilkS")
		)
		(fp_poly
			(pts
				(xy -1.0033 1.4859) (xy -1.0033 0.8001) (xy -1.1811 0.8001) (xy -1.1811 -0.8001) (xy -1.0033 -0.8001)
				(xy -1.0033 -1.4859) (xy 1.0033 -1.4859) (xy 1.0033 -0.8001) (xy 1.1811 -0.8001) (xy 1.1811 0.8001)
				(xy 1.0033 0.8001) (xy 1.0033 1.4859) (xy 0.2921 1.4859) (xy 0.2921 0.8001) (xy -0.2921 0.8001)
				(xy -0.2921 1.4859)
			)
			(stroke
				(width 0)
				(type default)
			)
			(fill no)
			(layer "F.CrtYd")
		)
		(fp_poly
			(pts
				(xy -1.0033 1.4859) (xy -1.0033 0.8001) (xy -1.1811 0.8001) (xy -1.1811 -0.8001) (xy -1.0033 -0.8001)
				(xy -1.0033 -1.4859) (xy 1.0033 -1.4859) (xy 1.0033 -0.8001) (xy 1.1811 -0.8001) (xy 1.1811 0.8001)
				(xy 1.0033 0.8001) (xy 1.0033 1.4859) (xy 0.2921 1.4859) (xy 0.2921 0.8001) (xy -0.2921 0.8001)
				(xy -0.2921 1.4859)
			)
			(stroke
				(width 0)
				(type default)
			)
			(fill no)
			(layer "F.Fab")
		)
		(pad "1" smd rect
			(at 0.65024 -0.93472)
			(size 0.3556 0.762)
			(layers "F.Cu" "F.Mask" "F.Paste")
			(net "Net_447")
		)
		(pad "2" smd rect
			(at 0 -0.93472)
			(size 0.3556 0.762)
			(layers "F.Cu" "F.Mask" "F.Paste")
			(net "P3V3_CPU_DELAY_IN")
		)
		(pad "3" smd rect
			(at -0.65024 -0.93472)
			(size 0.3556 0.762)
			(layers "F.Cu" "F.Mask" "F.Paste")
			(net "GND")
		)
		(pad "4" smd rect
			(at -0.65024 0.93472)
			(size 0.3556 0.762)
			(layers "F.Cu" "F.Mask" "F.Paste")
			(net "P3V3_CPU_PG_S1")
		)
		(pad "5" smd rect
			(at 0.65024 0.93472)
			(size 0.3556 0.762)
			(layers "F.Cu" "F.Mask" "F.Paste")
			(net "P3V3_STBY")
		)
	)
	(footprint ""
		(layer "F.Cu")
		(at 15.113 -69.215 90)
		(property "Reference" "R305"
			(at 0 0 90)
			(layer "F.SilkS")
			(hide yes)
			(effects
				(font
					(size 1.27 1.27)
				)
			)
		)
		(property "Value" "300R2F-GP"
			(at 1.7907 -1.1176 90)
			(unlocked yes)
			(layer "F.Fab")
			(hide yes)
			(effects
				(font
					(size 1.016 1.016)
					(thickness 0.1524)
				)
			)
		)
		(property "Device Type" "R402H16"
			(at 1.7907 -2.6416 90)
			(unlocked yes)
			(layer "F.Fab")
			(hide yes)
			(effects
				(font
					(size 1.016 1.016)
					(thickness 0.1524)
				)
			)
		)
		(duplicate_pad_numbers_are_jumpers no)
		(fp_rect
			(start -0.381 0.8382)
			(end 0.381 -0.8382)
			(stroke
				(width 0)
				(type default)
			)
			(fill no)
			(layer "F.CrtYd")
		)
		(fp_rect
			(start -0.381 0.8382)
			(end 0.381 -0.8382)
			(stroke
				(width 0)
				(type default)
			)
			(fill no)
			(layer "F.Fab")
		)
		(pad "1" smd custom
			(at 0 -0.4318 90)
			(size 0.127 0.127)
			(layers "F.Cu" "F.Mask" "F.Paste")
			(net "P3V3")
			(options
				(clearance outline)
				(anchor circle)
			)
			(primitives
				(gr_poly
					(pts
						(arc
							(start -0.2032 -0.2794)
							(mid -0.239121 -0.264521)
							(end -0.254 -0.2286)
						)
						(arc
							(start -0.254 0.2286)
							(mid -0.239121 0.264521)
							(end -0.2032 0.2794)
						)
						(arc
							(start 0.2032 0.2794)
							(mid 0.239121 0.264521)
							(end 0.254 0.2286)
						)
						(arc
							(start 0.254 -0.2286)
							(mid 0.239121 -0.264521)
							(end 0.2032 -0.2794)
						)
					)
					(width 0)
					(fill yes)
				)
			)
		)
		(pad "2" smd custom
			(at 0 0.4318 90)
			(size 0.127 0.127)
			(layers "F.Cu" "F.Mask" "F.Paste")
			(net "LED_NGFF_DAS_R")
			(options
				(clearance outline)
				(anchor circle)
			)
			(primitives
				(gr_poly
					(pts
						(arc
							(start -0.2032 -0.2794)
							(mid -0.239121 -0.264521)
							(end -0.254 -0.2286)
						)
						(arc
							(start -0.254 0.2286)
							(mid -0.239121 0.264521)
							(end -0.2032 0.2794)
						)
						(arc
							(start 0.2032 0.2794)
							(mid 0.239121 0.264521)
							(end 0.254 0.2286)
						)
						(arc
							(start 0.254 -0.2286)
							(mid 0.239121 -0.264521)
							(end 0.2032 -0.2794)
						)
					)
					(width 0)
					(fill yes)
				)
			)
		)
	)
	(footprint ""
		(layer "F.Cu")
		(at 57.404 -56.769)
		(property "Reference" "PC145"
			(at 0 0 0)
			(layer "F.SilkS")
			(hide yes)
			(effects
				(font
					(size 1.27 1.27)
				)
			)
		)
		(property "Value" "SC47U6D3V5MX-1-GP"
			(at -0.0762 -6.1214 0)
			(unlocked yes)
			(layer "F.Fab")
			(hide yes)
			(effects
				(font
					(size 1.016 1.016)
					(thickness 0.1524)
				)
			)
		)
		(property "Device Type" "C805H54"
			(at -0.0762 -8.1534 0)
			(unlocked yes)
			(layer "F.Fab")
			(hide yes)
			(effects
				(font
					(size 1.016 1.016)
					(thickness 0.1524)
				)
			)
		)
		(duplicate_pad_numbers_are_jumpers no)
		(fp_line
			(start 0.6096 0)
			(end -0.6096 0)
			(stroke
				(width 0.3048)
				(type default)
			)
			(layer "F.SilkS")
		)
		(fp_poly
			(pts
				(xy -0.9017 1.4351) (xy 0.9017 1.4351) (xy 0.9017 -1.4351) (xy -0.9017 -1.4351)
			)
			(stroke
				(width 0)
				(type default)
			)
			(fill no)
			(layer "F.CrtYd")
		)
		(fp_poly
			(pts
				(xy 0.9017 1.4351) (xy 0.9017 -1.4351) (xy -0.9017 -1.4351) (xy -0.9017 1.4351)
			)
			(stroke
				(width 0)
				(type default)
			)
			(fill no)
			(layer "F.Fab")
		)
		(pad "1" smd rect
			(at 0 -0.8382)
			(size 1.5494 0.9398)
			(layers "F.Cu" "F.Mask" "F.Paste")
			(net "PVCCP")
		)
		(pad "2" smd rect
			(at 0 0.8382)
			(size 1.5494 0.9398)
			(layers "F.Cu" "F.Mask" "F.Paste")
			(net "GND")
		)
	)
	(footprint ""
		(layer "F.Cu")
		(at 15.8496 -53.7972 -90)
		(property "Reference" "PR48"
			(at 0 0 270)
			(layer "F.SilkS")
			(hide yes)
			(effects
				(font
					(size 1.27 1.27)
				)
			)
		)
		(property "Value" "0R2J-2-GP"
			(at 1.7907 -1.1176 270)
			(unlocked yes)
			(layer "F.Fab")
			(hide yes)
			(effects
				(font
					(size 1.016 1.016)
					(thickness 0.1524)
				)
			)
		)
		(property "Device Type" "R402H16"
			(at 1.7907 -2.6416 270)
			(unlocked yes)
			(layer "F.Fab")
			(hide yes)
			(effects
				(font
					(size 1.016 1.016)
					(thickness 0.1524)
				)
			)
		)
		(duplicate_pad_numbers_are_jumpers no)
		(fp_rect
			(start -0.381 0.8382)
			(end 0.381 -0.8382)
			(stroke
				(width 0)
				(type default)
			)
			(fill no)
			(layer "F.CrtYd")
		)
		(fp_rect
			(start -0.381 0.8382)
			(end 0.381 -0.8382)
			(stroke
				(width 0)
				(type default)
			)
			(fill no)
			(layer "F.Fab")
		)
		(pad "1" smd custom
			(at 0 -0.4318 270)
			(size 0.127 0.127)
			(layers "F.Cu" "F.Mask" "F.Paste")
			(net "PVCCP_PVNN_R_VRHOT#")
			(options
				(clearance outline)
				(anchor circle)
			)
			(primitives
				(gr_poly
					(pts
						(arc
							(start -0.2032 -0.2794)
							(mid -0.239121 -0.264521)
							(end -0.254 -0.2286)
						)
						(arc
							(start -0.254 0.2286)
							(mid -0.239121 0.264521)
							(end -0.2032 0.2794)
						)
						(arc
							(start 0.2032 0.2794)
							(mid 0.239121 0.264521)
							(end 0.254 0.2286)
						)
						(arc
							(start 0.254 -0.2286)
							(mid 0.239121 -0.264521)
							(end 0.2032 -0.2794)
						)
					)
					(width 0)
					(fill yes)
				)
			)
		)
		(pad "2" smd custom
			(at 0 0.4318 270)
			(size 0.127 0.127)
			(layers "F.Cu" "F.Mask" "F.Paste")
			(net "PVCCP_PVNN_VRHOT#")
			(options
				(clearance outline)
				(anchor circle)
			)
			(primitives
				(gr_poly
					(pts
						(arc
							(start -0.2032 -0.2794)
							(mid -0.239121 -0.264521)
							(end -0.254 -0.2286)
						)
						(arc
							(start -0.254 0.2286)
							(mid -0.239121 0.264521)
							(end -0.2032 0.2794)
						)
						(arc
							(start 0.2032 0.2794)
							(mid 0.239121 0.264521)
							(end 0.254 0.2286)
						)
						(arc
							(start 0.254 -0.2286)
							(mid 0.239121 -0.264521)
							(end 0.2032 -0.2794)
						)
					)
					(width 0)
					(fill yes)
				)
			)
		)
	)
	(footprint ""
		(layer "F.Cu")
		(at 170.688 -33.655 -90)
		(property "Reference" "PU8"
			(at 0 0 270)
			(layer "F.SilkS")
			(hide yes)
			(effects
				(font
					(size 1.27 1.27)
				)
			)
		)
		(property "Value" "LD1117AG-12-AA3-A-R-GP"
			(at -0.0508 -10.3632 270)
			(unlocked yes)
			(layer "F.Fab")
			(hide yes)
			(effects
				(font
					(size 1.016 1.016)
					(thickness 0.1524)
				)
			)
		)
		(property "Device Type" "SOT-223H71"
			(at -0.1524 -12.3952 270)
			(unlocked yes)
			(layer "F.Fab")
			(hide yes)
			(effects
				(font
					(size 1.016 1.016)
					(thickness 0.1524)
				)
			)
		)
		(duplicate_pad_numbers_are_jumpers no)
		(fp_poly
			(pts
				(xy -2.3749 1.0922) (xy -1.9431 1.524) (xy -2.8067 1.524)
			)
			(stroke
				(width 0)
				(type default)
			)
			(fill yes)
			(layer "F.SilkS")
		)
		(fp_poly
			(pts
				(xy 3.048 1.0795) (xy 3.048 -0.8001) (xy 3.5052 -0.8001) (xy 3.5052 -4.8133) (xy 1.8796 -4.8133)
				(xy 1.8796 -6.6675) (xy -1.8796 -6.6675) (xy -1.8796 -4.8133) (xy -3.5052 -4.8133) (xy -3.5052 -0.8001)
				(xy -3.048 -0.8001) (xy -3.048 1.0795)
			)
			(stroke
				(width 0)
				(type default)
			)
			(fill no)
			(layer "F.CrtYd")
		)
		(fp_poly
			(pts
				(xy 3.048 1.0795) (xy 3.048 -0.5207) (xy 3.048 -0.6731) (xy 3.048 -0.8001) (xy 3.5052 -0.8001) (xy 3.5052 -4.6863)
				(xy 3.5052 -4.8133) (xy 1.905 -4.8133) (xy 1.8796 -4.8133) (xy 1.8796 -6.6675) (xy -1.8796 -6.6675)
				(xy -1.8796 -4.8133) (xy -1.905 -4.8133) (xy -3.5052 -4.8133) (xy -3.5052 -4.6863) (xy -3.5052 -0.8001)
				(xy -3.048 -0.8001) (xy -3.048 -0.6731) (xy -3.048 1.0795)
			)
			(stroke
				(width 0)
				(type default)
			)
			(fill no)
			(layer "F.Fab")
		)
		(pad "1" smd rect
			(at -2.286 0 270)
			(size 1.27 1.905)
			(layers "F.Cu" "F.Mask" "F.Paste")
			(net "GND")
		)
		(pad "2" smd custom
			(at 0 0 270)
			(size 0.8763 0.8763)
			(layers "F.Cu" "F.Mask" "F.Paste")
			(net "P1V2_STBY_LDO_OUT1")
			(options
				(clearance outline)
				(anchor circle)
			)
			(primitives
				(gr_poly
					(pts
						(xy 1.7526 -1.8415) (xy 0.381 -1.8415) (xy 0.381 1.8415) (xy 0.635 1.8415) (xy 0.635 3.7465) (xy -0.635 3.7465)
						(xy -0.635 1.8415) (xy -0.381 1.8415) (xy -0.381 -1.8415) (xy -1.7526 -1.8415) (xy -1.7526 -3.7465)
						(xy 1.7526 -3.7465)
					)
					(width 0)
					(fill yes)
				)
			)
		)
		(pad "3" smd rect
			(at 2.286 0 270)
			(size 1.27 1.905)
			(layers "F.Cu" "F.Mask" "F.Paste")
			(net "P1V8_STBY_LDO_IN1")
		)
	)
	(footprint ""
		(layer "F.Cu")
		(at 5.715 -39.6748 90)
		(property "Reference" "PL9"
			(at 0 0 90)
			(layer "F.SilkS")
			(hide yes)
			(effects
				(font
					(size 1.27 1.27)
				)
			)
		)
		(property "Value" "BLM21PG220SN1DGP"
			(at 0.0381 -2.7178 90)
			(unlocked yes)
			(layer "F.Fab")
			(hide yes)
			(effects
				(font
					(size 1.016 1.016)
					(thickness 0.1524)
				)
			)
		)
		(property "Device Type" "L20125H42"
			(at 0.0381 -4.2418 90)
			(unlocked yes)
			(layer "F.Fab")
			(hide yes)
			(effects
				(font
					(size 1.016 1.016)
					(thickness 0.1524)
				)
			)
		)
		(duplicate_pad_numbers_are_jumpers no)
		(fp_line
			(start 0.5461 -0.1397)
			(end -0.5461 -0.1397)
			(stroke
				(width 0.1524)
				(type default)
			)
			(layer "F.SilkS")
		)
		(fp_line
			(start -0.5461 -0.1397)
			(end -0.5461 0.1397)
			(stroke
				(width 0.1524)
				(type default)
			)
			(layer "F.SilkS")
		)
		(fp_line
			(start -0.5461 0)
			(end 0.5461 0)
			(stroke
				(width 0.1524)
				(type default)
			)
			(layer "F.SilkS")
		)
		(fp_line
			(start 0.5461 0.1397)
			(end 0.5461 -0.1397)
			(stroke
				(width 0.1524)
				(type default)
			)
			(layer "F.SilkS")
		)
		(fp_line
			(start -0.5461 0.1397)
			(end 0.5461 0.1397)
			(stroke
				(width 0.1524)
				(type default)
			)
			(layer "F.SilkS")
		)
		(fp_poly
			(pts
				(xy -0.8001 1.4351) (xy 0.8001 1.4351) (xy 0.8001 -1.4351) (xy -0.8001 -1.4351)
			)
			(stroke
				(width 0)
				(type default)
			)
			(fill no)
			(layer "F.CrtYd")
		)
		(fp_rect
			(start -0.8001 1.4351)
			(end 0.8001 -1.4351)
			(stroke
				(width 0)
				(type default)
			)
			(fill no)
			(layer "F.Fab")
		)
		(pad "1" smd rect
			(at 0 -0.8382 90)
			(size 1.3462 0.9398)
			(layers "F.Cu" "F.Mask" "F.Paste")
			(net "P12V")
		)
		(pad "2" smd rect
			(at 0 0.8382 90)
			(size 1.3462 0.9398)
			(layers "F.Cu" "F.Mask" "F.Paste")
			(net "P3V3_STBY_VIN")
		)
	)
	(footprint ""
		(layer "F.Cu")
		(at 160.401 -25.527)
		(property "Reference" "SW2"
			(at 0 0 0)
			(layer "F.SilkS")
			(hide yes)
			(effects
				(font
					(size 1.27 1.27)
				)
			)
		)
		(property "Value" "SW-DIP-2P-1-GP"
			(at -2.7178 -1.8796 0)
			(unlocked yes)
			(layer "F.Fab")
			(hide yes)
			(effects
				(font
					(size 1.016 1.016)
					(thickness 0.1524)
				)
			)
		)
		(property "Device Type" "EM-01-V"
			(at -2.7178 -3.4036 0)
			(unlocked yes)
			(layer "F.Fab")
			(hide yes)
			(effects
				(font
					(size 1.016 1.016)
					(thickness 0.1524)
				)
			)
		)
		(duplicate_pad_numbers_are_jumpers no)
		(fp_line
			(start 0 -2.286)
			(end 0 -2.794)
			(stroke
				(width 0.1524)
				(type default)
			)
			(layer "F.SilkS")
		)
		(fp_line
			(start 0 1.778)
			(end 0.635 -1.778)
			(stroke
				(width 0.1524)
				(type default)
			)
			(layer "F.SilkS")
		)
		(fp_line
			(start 0 2.286)
			(end 0 2.794)
			(stroke
				(width 0.1524)
				(type default)
			)
			(layer "F.SilkS")
		)
		(fp_circle
			(center 0 -2.032)
			(end 0.254 -2.032)
			(stroke
				(width 0.1524)
				(type default)
			)
			(fill no)
			(layer "F.SilkS")
		)
		(fp_circle
			(center 0 2.032)
			(end 0.254 2.032)
			(stroke
				(width 0.1524)
				(type default)
			)
			(fill no)
			(layer "F.SilkS")
		)
		(fp_poly
			(pts
				(xy -0.00889 -5.541264) (xy 0.62611 -6.176264) (xy -0.64389 -6.176264)
			)
			(stroke
				(width 0)
				(type default)
			)
			(fill yes)
			(layer "F.SilkS")
		)
		(fp_rect
			(start -1.4732 5.5372)
			(end 1.4732 -5.5372)
			(stroke
				(width 0)
				(type default)
			)
			(fill no)
			(layer "F.CrtYd")
		)
		(fp_rect
			(start -1.4732 5.5372)
			(end 1.4732 -5.5372)
			(stroke
				(width 0)
				(type default)
			)
			(fill no)
			(layer "F.Fab")
		)
		(pad "1" smd rect
			(at 0 -4.400042)
			(size 1.0922 2.0066)
			(layers "F.Cu" "F.Mask" "F.Paste")
			(net "DISABLE_H")
		)
		(pad "2" smd rect
			(at 0 4.400042)
			(size 1.0922 2.0066)
			(layers "F.Cu" "F.Mask" "F.Paste")
			(net "DISABLE")
		)
	)
	(footprint ""
		(layer "F.Cu")
		(at 142.748 -19.685)
		(property "Reference" "LED2"
			(at 0 0 0)
			(layer "F.SilkS")
			(hide yes)
			(effects
				(font
					(size 1.27 1.27)
				)
			)
		)
		(property "Value" "LED-YG-51-GP"
			(at -2.6924 -1.4224 0)
			(unlocked yes)
			(layer "F.Fab")
			(hide yes)
			(effects
				(font
					(size 1.016 1.016)
					(thickness 0.1524)
				)
			)
		)
		(property "Device Type" "LED1608AKH40"
			(at -2.6924 -2.9464 0)
			(unlocked yes)
			(layer "F.Fab")
			(hide yes)
			(effects
				(font
					(size 1.016 1.016)
					(thickness 0.1524)
				)
			)
		)
		(duplicate_pad_numbers_are_jumpers no)
		(fp_line
			(start -0.5334 1.3081)
			(end 0.5334 1.3081)
			(stroke
				(width 0.254)
				(type default)
			)
			(layer "F.SilkS")
		)
		(fp_rect
			(start -0.6604 1.1811)
			(end 0.6604 -1.1811)
			(stroke
				(width 0)
				(type default)
			)
			(fill no)
			(layer "F.CrtYd")
		)
		(fp_rect
			(start -0.6604 1.1811)
			(end 0.6604 -1.1811)
			(stroke
				(width 0)
				(type default)
			)
			(fill no)
			(layer "F.Fab")
		)
		(pad "A" smd rect
			(at 0 -0.652526)
			(size 1.0668 0.8128)
			(layers "F.Cu" "F.Mask" "F.Paste")
			(net "C_CONF_DONE")
		)
		(pad "K" smd rect
			(at 0 0.652526)
			(size 1.0668 0.8128)
			(layers "F.Cu" "F.Mask" "F.Paste")
			(net "GND")
		)
	)
)
